# S9S_MB_2U (Grand Teton) — schematic netlist excerpt (pin names and nets, part order shuffled) for the footprints in the layout excerpt that follows; sources: Cadence DE-HDL packaged netlist, KiCad conversion of 03242023_DA0F0TMBIJ0_F0T_Motherboard_J_brd_V01_OCP.brd

R5377  Q_RES  0 5% CHIP  pkg 0402LF  page 190 : A = HDD_ACTIVITY_BUF_N ; B = PU_BUFFER_HDD_ACTIVITY
R1495  Q_RES  10K 1% CHIP  pkg 0402LF  page 215 : A = PD_FORCE_PWRON ; B = GND

(kicad_pcb
	(version 20260206)
	(generator "pcbnew")
	(generator_version "10.0")
	(general
		(thickness 1.6)
		(legacy_teardrops no)
	)
	(paper "A4")
	(title_block
		(title "03242023_DA0F0TMBIJ0_F0T_Motherboard_J_brd_V01_OCP.brd")
		(comment 1 "Grand Teton / footprints 1406-1407 of 6105")
	)
	(layers
		(0 "F.Cu" signal "TOP")
		(4 "In1.Cu" signal "GND")
		(6 "In2.Cu" signal "IN1")
		(8 "In3.Cu" signal "GND1")
		(10 "In4.Cu" signal "IN2")
		(12 "In5.Cu" signal "GND2")
		(14 "In6.Cu" signal "IN3")
		(16 "In7.Cu" signal "GND3")
		(18 "In8.Cu" signal "VCC")
		(20 "In9.Cu" signal "VCC1")
		(22 "In10.Cu" signal "GND4")
		(24 "In11.Cu" signal "IN4")
		(26 "In12.Cu" signal "GND5")
		(28 "In13.Cu" signal "IN5")
		(30 "In14.Cu" signal "GND6")
		(32 "In15.Cu" signal "IN6")
		(34 "In16.Cu" signal "GND7")
		(2 "B.Cu" signal "BOTTOM")
		(9 "F.Adhes" user "F.Adhesive")
		(11 "B.Adhes" user "B.Adhesive")
		(13 "F.Paste" user "Package Geometry/Pastemask Top")
		(15 "B.Paste" user "Package Geometry/Pastemask Bottom")
		(5 "F.SilkS" user "Ref Des/Silkscreen Top")
		(7 "B.SilkS" user "Ref Des/Silkscreen Bottom")
		(1 "F.Mask" user "Board Geometry/Soldermask Top")
		(3 "B.Mask" user "Board Geometry/Soldermask Bottom")
		(17 "Dwgs.User" user "User.Drawings")
		(19 "Cmts.User" user "User.Comments")
		(21 "Eco1.User" user "User.Eco1")
		(23 "Eco2.User" user "User.Eco2")
		(25 "Edge.Cuts" user "Board Geometry/Outline")
		(27 "Margin" user)
		(31 "F.CrtYd" user "Package Geometry/Place Bound Top")
		(29 "B.CrtYd" user "Package Geometry/Place Bound Bottom")
		(35 "F.Fab" user "Ref Des/Assembly Top")
		(33 "B.Fab" user "Ref Des/Assembly Bottom")
	)
	(footprint ""
		(layer "F.Cu")
		(at 131.318 -156.398468 180)
		(property "Reference" "R1495"
			(at 0 0 180)
			(layer "F.SilkS")
			(hide yes)
			(effects
				(font
					(size 1.27 1.27)
				)
			)
		)
		(property "Value" ""
			(at 0 0 180)
			(layer "F.Fab")
			(effects
				(font
					(size 1.27 1.27)
				)
			)
		)
		(duplicate_pad_numbers_are_jumpers no)
		(fp_line
			(start 0.7874 0.4064)
			(end -0.7874 0.4064)
			(stroke
				(width 0.1524)
				(type default)
			)
			(layer "F.SilkS")
		)
		(fp_line
			(start 0.7874 -0.4064)
			(end 0.7874 0.4064)
			(stroke
				(width 0.1524)
				(type default)
			)
			(layer "F.SilkS")
		)
		(fp_line
			(start -0.7874 0.4064)
			(end -0.7874 -0.4064)
			(stroke
				(width 0.1524)
				(type default)
			)
			(layer "F.SilkS")
		)
		(fp_line
			(start -0.7874 -0.4064)
			(end 0.7874 -0.4064)
			(stroke
				(width 0.1524)
				(type default)
			)
			(layer "F.SilkS")
		)
		(fp_line
			(start 0.67945 0.3048)
			(end 0.120396 0.3048)
			(stroke
				(width 0.1)
				(type default)
			)
			(layer "F.Fab")
		)
		(fp_line
			(start 0.67945 -0.3048)
			(end 0.67945 0.3048)
			(stroke
				(width 0.1)
				(type default)
			)
			(layer "F.Fab")
		)
		(fp_line
			(start 0.12065 -0.2794)
			(end 0.12065 -0.3048)
			(stroke
				(width 0.1)
				(type default)
			)
			(layer "F.Fab")
		)
		(fp_line
			(start 0.12065 -0.3048)
			(end 0.67945 -0.3048)
			(stroke
				(width 0.1)
				(type default)
			)
			(layer "F.Fab")
		)
		(fp_line
			(start 0.120396 0.3048)
			(end 0.120396 0.2794)
			(stroke
				(width 0.1)
				(type default)
			)
			(layer "F.Fab")
		)
		(fp_line
			(start 0.120396 0.2794)
			(end -0.12065 0.2794)
			(stroke
				(width 0.1)
				(type default)
			)
			(layer "F.Fab")
		)
		(fp_line
			(start -0.12065 0.3048)
			(end -0.67945 0.3048)
			(stroke
				(width 0.1)
				(type default)
			)
			(layer "F.Fab")
		)
		(fp_line
			(start -0.12065 0.2794)
			(end -0.12065 0.3048)
			(stroke
				(width 0.1)
				(type default)
			)
			(layer "F.Fab")
		)
		(fp_line
			(start -0.12065 -0.2794)
			(end 0.12065 -0.2794)
			(stroke
				(width 0.1)
				(type default)
			)
			(layer "F.Fab")
		)
		(fp_line
			(start -0.12065 -0.305054)
			(end -0.12065 -0.2794)
			(stroke
				(width 0.1)
				(type default)
			)
			(layer "F.Fab")
		)
		(fp_line
			(start -0.67945 0.3048)
			(end -0.67945 -0.305054)
			(stroke
				(width 0.1)
				(type default)
			)
			(layer "F.Fab")
		)
		(fp_line
			(start -0.67945 -0.305054)
			(end -0.12065 -0.305054)
			(stroke
				(width 0.1)
				(type default)
			)
			(layer "F.Fab")
		)
		(pad "1" smd circle
			(at -0.40005 0 180)
			(size 0 0)
			(layers "F.Cu" "F.Mask" "F.Paste")
			(net "PD_FORCE_PWRON")
		)
		(pad "2" smd circle
			(at 0.40005 0 180)
			(size 0 0)
			(layers "F.Cu" "F.Mask" "F.Paste")
			(net "GND")
		)
	)
	(footprint ""
		(layer "F.Cu")
		(at 142.54988 -46.954948)
		(property "Reference" "R5377"
			(at 0 0 0)
			(layer "F.SilkS")
			(hide yes)
			(effects
				(font
					(size 1.27 1.27)
				)
			)
		)
		(property "Value" ""
			(at 0 0 0)
			(layer "F.Fab")
			(effects
				(font
					(size 1.27 1.27)
				)
			)
		)
		(duplicate_pad_numbers_are_jumpers no)
		(fp_line
			(start -0.7874 -0.4064)
			(end 0.7874 -0.4064)
			(stroke
				(width 0.1524)
				(type default)
			)
			(layer "F.SilkS")
		)
		(fp_line
			(start -0.7874 0.4064)
			(end -0.7874 -0.4064)
			(stroke
				(width 0.1524)
				(type default)
			)
			(layer "F.SilkS")
		)
		(fp_line
			(start 0.7874 -0.4064)
			(end 0.7874 0.4064)
			(stroke
				(width 0.1524)
				(type default)
			)
			(layer "F.SilkS")
		)
		(fp_line
			(start 0.7874 0.4064)
			(end -0.7874 0.4064)
			(stroke
				(width 0.1524)
				(type default)
			)
			(layer "F.SilkS")
		)
		(fp_line
			(start -0.67945 -0.305054)
			(end -0.12065 -0.305054)
			(stroke
				(width 0.1)
				(type default)
			)
			(layer "F.Fab")
		)
		(fp_line
			(start -0.67945 0.3048)
			(end -0.67945 -0.305054)
			(stroke
				(width 0.1)
				(type default)
			)
			(layer "F.Fab")
		)
		(fp_line
			(start -0.12065 -0.305054)
			(end -0.12065 -0.2794)
			(stroke
				(width 0.1)
				(type default)
			)
			(layer "F.Fab")
		)
		(fp_line
			(start -0.12065 -0.2794)
			(end 0.12065 -0.2794)
			(stroke
				(width 0.1)
				(type default)
			)
			(layer "F.Fab")
		)
		(fp_line
			(start -0.12065 0.2794)
			(end -0.12065 0.3048)
			(stroke
				(width 0.1)
				(type default)
			)
			(layer "F.Fab")
		)
		(fp_line
			(start -0.12065 0.3048)
			(end -0.67945 0.3048)
			(stroke
				(width 0.1)
				(type default)
			)
			(layer "F.Fab")
		)
		(fp_line
			(start 0.120396 0.2794)
			(end -0.12065 0.2794)
			(stroke
				(width 0.1)
				(type default)
			)
			(layer "F.Fab")
		)
		(fp_line
			(start 0.120396 0.3048)
			(end 0.120396 0.2794)
			(stroke
				(width 0.1)
				(type default)
			)
			(layer "F.Fab")
		)
		(fp_line
			(start 0.12065 -0.3048)
			(end 0.67945 -0.3048)
			(stroke
				(width 0.1)
				(type default)
			)
			(layer "F.Fab")
		)
		(fp_line
			(start 0.12065 -0.2794)
			(end 0.12065 -0.3048)
			(stroke
				(width 0.1)
				(type default)
			)
			(layer "F.Fab")
		)
		(fp_line
			(start 0.67945 -0.3048)
			(end 0.67945 0.3048)
			(stroke
				(width 0.1)
				(type default)
			)
			(layer "F.Fab")
		)
		(fp_line
			(start 0.67945 0.3048)
			(end 0.120396 0.3048)
			(stroke
				(width 0.1)
				(type default)
			)
			(layer "F.Fab")
		)
		(pad "1" smd circle
			(at -0.40005 0)
			(size 0 0)
			(layers "F.Cu" "F.Mask" "F.Paste")
			(net "HDD_ACTIVITY_BUF_N")
		)
		(pad "2" smd circle
			(at 0.40005 0)
			(size 0 0)
			(layers "F.Cu" "F.Mask" "F.Paste")
			(net "PU_BUFFER_HDD_ACTIVITY")
		)
	)
)
